(kicad_pcb
	(version 20260206)
	(generator "pcbnew")
	(generator_version "10.0")
	(general
		(thickness 1.6)
		(legacy_teardrops no)
	)
	(paper "A4")
	(title_block
		(title "03242023_DA0F0TMBIJ0_F0T_Motherboard_J_brd_V01_OCP.brd")
		(comment 1 "Grand Teton / footprint 1682 of 6105 (U1), pads 534-640 of 4677")
	)
	(layers
		(0 "F.Cu" signal "TOP")
		(4 "In1.Cu" signal "GND")
		(6 "In2.Cu" signal "IN1")
		(8 "In3.Cu" signal "GND1")
		(10 "In4.Cu" signal "IN2")
		(12 "In5.Cu" signal "GND2")
		(14 "In6.Cu" signal "IN3")
		(16 "In7.Cu" signal "GND3")
		(18 "In8.Cu" signal "VCC")
		(20 "In9.Cu" signal "VCC1")
		(22 "In10.Cu" signal "GND4")
		(24 "In11.Cu" signal "IN4")
		(26 "In12.Cu" signal "GND5")
		(28 "In13.Cu" signal "IN5")
		(30 "In14.Cu" signal "GND6")
		(32 "In15.Cu" signal "IN6")
		(34 "In16.Cu" signal "GND7")
		(2 "B.Cu" signal "BOTTOM")
		(9 "F.Adhes" user "F.Adhesive")
		(11 "B.Adhes" user "B.Adhesive")
		(13 "F.Paste" user "Package Geometry/Pastemask Top")
		(15 "B.Paste" user "Package Geometry/Pastemask Bottom")
		(5 "F.SilkS" user "Ref Des/Silkscreen Top")
		(7 "B.SilkS" user "Ref Des/Silkscreen Bottom")
		(1 "F.Mask" user "Board Geometry/Soldermask Top")
		(3 "B.Mask" user "Board Geometry/Soldermask Bottom")
		(17 "Dwgs.User" user "User.Drawings")
		(19 "Cmts.User" user "User.Comments")
		(21 "Eco1.User" user "User.Eco1")
		(23 "Eco2.User" user "User.Eco2")
		(25 "Edge.Cuts" user "Board Geometry/Outline")
		(27 "Margin" user)
		(31 "F.CrtYd" user "Package Geometry/Place Bound Top")
		(29 "B.CrtYd" user "Package Geometry/Place Bound Bottom")
		(35 "F.Fab" user "Ref Des/Assembly Top")
		(33 "B.Fab" user "Ref Des/Assembly Bottom")
	)
	(footprint ""
		(layer "F.Cu")
		(at 111.93018 -251.76988 90)
		(property "Reference" "U1"
			(at -74.913236 41.548812 0)
			(unlocked yes)
			(layer "F.SilkS")
			(effects
				(font
					(size 1.6002 1.1938)
					(thickness 0.1524)
				)
				(justify left)
			)
		)
		(property "Value" ""
			(at 0 0 90)
			(layer "F.Fab")
			(effects
				(font
					(size 1.27 1.27)
				)
			)
		)
		(duplicate_pad_numbers_are_jumpers no)
		(pad "AM26" smd circle
			(at -17.07769 -12.507468 270)
			(size 0.4318 0.4318)
			(layers "F.Cu" "F.Mask" "F.Paste")
			(net "GND")
		)
		(pad "AM28" smd circle
			(at -15.450058 -12.507468 270)
			(size 0.4318 0.4318)
			(layers "F.Cu" "F.Mask" "F.Paste")
			(net "GND")
		)
		(pad "AM30" smd circle
			(at -13.822426 -12.507468 270)
			(size 0.4318 0.4318)
			(layers "F.Cu" "F.Mask" "F.Paste")
			(net "GND")
		)
		(pad "AM32" smd circle
			(at -12.19454 -12.507468 270)
			(size 0.4318 0.4318)
			(layers "F.Cu" "F.Mask" "F.Paste")
			(net "GND")
		)
		(pad "AM34" smd circle
			(at -10.566654 -12.507468 270)
			(size 0.4318 0.4318)
			(layers "F.Cu" "F.Mask" "F.Paste")
			(net "GND")
		)
		(pad "AM36" smd circle
			(at -8.939022 -12.507468 270)
			(size 0.4318 0.4318)
			(layers "F.Cu" "F.Mask" "F.Paste")
			(net "GND")
		)
		(pad "AM38" smd circle
			(at -7.311136 -12.507468 270)
			(size 0.4318 0.4318)
			(layers "F.Cu" "F.Mask" "F.Paste")
			(net "GND")
		)
		(pad "AM40" smd circle
			(at -5.68325 -12.507468 270)
			(size 0.4318 0.4318)
			(layers "F.Cu" "F.Mask" "F.Paste")
			(net "GND")
		)
		(pad "AM42" smd circle
			(at -4.055618 -12.507468 270)
			(size 0.4318 0.4318)
			(layers "F.Cu" "F.Mask" "F.Paste")
			(net "GND")
		)
		(pad "AM44" smd circle
			(at -2.427732 -12.507468 270)
			(size 0.4318 0.4318)
			(layers "F.Cu" "F.Mask" "F.Paste")
			(net "GND")
		)
		(pad "AM47" smd circle
			(at 1.613916 -12.397486 270)
			(size 0.4318 0.4318)
			(layers "F.Cu" "F.Mask" "F.Paste")
			(net "GND")
		)
		(pad "AM49" smd circle
			(at 3.241802 -12.397486 270)
			(size 0.4318 0.4318)
			(layers "F.Cu" "F.Mask" "F.Paste")
			(net "GND")
		)
		(pad "AM51" smd circle
			(at 4.869434 -12.397486 270)
			(size 0.4318 0.4318)
			(layers "F.Cu" "F.Mask" "F.Paste")
			(net "GND")
		)
		(pad "AM53" smd circle
			(at 6.49732 -12.397486 270)
			(size 0.4318 0.4318)
			(layers "F.Cu" "F.Mask" "F.Paste")
			(net "GND")
		)
		(pad "AM55" smd circle
			(at 8.124952 -12.397486 270)
			(size 0.4318 0.4318)
			(layers "F.Cu" "F.Mask" "F.Paste")
			(net "GND")
		)
		(pad "AM57" smd circle
			(at 9.752838 -12.397486 270)
			(size 0.4318 0.4318)
			(layers "F.Cu" "F.Mask" "F.Paste")
			(net "GND")
		)
		(pad "AM59" smd circle
			(at 11.380724 -12.397486 270)
			(size 0.4318 0.4318)
			(layers "F.Cu" "F.Mask" "F.Paste")
			(net "GND")
		)
		(pad "AM61" smd circle
			(at 13.008356 -12.397486 270)
			(size 0.4318 0.4318)
			(layers "F.Cu" "F.Mask" "F.Paste")
			(net "GND")
		)
		(pad "AM63" smd circle
			(at 14.635988 -12.397486 270)
			(size 0.4318 0.4318)
			(layers "F.Cu" "F.Mask" "F.Paste")
			(net "GND")
		)
		(pad "AM65" smd circle
			(at 16.263874 -12.397486 270)
			(size 0.4318 0.4318)
			(layers "F.Cu" "F.Mask" "F.Paste")
			(net "GND")
		)
		(pad "AM67" smd circle
			(at 17.89176 -12.397486 270)
			(size 0.4318 0.4318)
			(layers "F.Cu" "F.Mask" "F.Paste")
			(net "GND")
		)
		(pad "AM69" smd circle
			(at 19.519392 -12.397486 270)
			(size 0.4318 0.4318)
			(layers "F.Cu" "F.Mask" "F.Paste")
			(net "GND")
		)
		(pad "AM71" smd circle
			(at 21.147278 -12.397486 270)
			(size 0.4318 0.4318)
			(layers "F.Cu" "F.Mask" "F.Paste")
			(net "GND")
		)
		(pad "AM73" smd circle
			(at 22.77491 -12.397486 270)
			(size 0.4318 0.4318)
			(layers "F.Cu" "F.Mask" "F.Paste")
			(net "GND")
		)
		(pad "AM75" smd circle
			(at 24.402796 -12.397486 270)
			(size 0.4318 0.4318)
			(layers "F.Cu" "F.Mask" "F.Paste")
			(net "GND")
		)
		(pad "AM77" smd circle
			(at 26.030682 -12.397486 270)
			(size 0.4318 0.4318)
			(layers "F.Cu" "F.Mask" "F.Paste")
			(net "GND")
		)
		(pad "AM79" smd circle
			(at 27.658314 -12.397486 270)
			(size 0.4318 0.4318)
			(layers "F.Cu" "F.Mask" "F.Paste")
			(net "PVCCFA_EHV_FIVRA_CPU1")
		)
		(pad "AM81" smd circle
			(at 29.2862 -12.397486 270)
			(size 0.4318 0.4318)
			(layers "F.Cu" "F.Mask" "F.Paste")
			(net "UPI_CPU1_CPU0_P2P2_DN<12>")
		)
		(pad "AM83" smd circle
			(at 30.914086 -12.397486 270)
			(size 0.4318 0.4318)
			(layers "F.Cu" "F.Mask" "F.Paste")
			(net "UPI_CPU1_CPU0_P2P2_DP<13>")
		)
		(pad "AM85" smd circle
			(at 32.541718 -12.397486 270)
			(size 0.4318 0.4318)
			(layers "F.Cu" "F.Mask" "F.Paste")
			(net "PVCCFA_EHV_FIVRA_CPU1")
		)
		(pad "AM87" smd circle
			(at 34.169604 -12.397486 270)
			(size 0.4318 0.4318)
			(layers "F.Cu" "F.Mask" "F.Paste")
			(net "P5E_CPU1_PE4_TX_DP<10>")
		)
		(pad "AM89" smd circle
			(at 35.797236 -12.397486 270)
			(size 0.4318 0.4318)
			(layers "F.Cu" "F.Mask" "F.Paste")
			(net "PVCCFA_EHV_FIVRA_CPU1")
		)
		(pad "AM91" smd oval
			(at 37.425122 -12.397486)
			(size 0.381 0.4826)
			(drill
				(offset 0 -0.0508)
			)
			(layers "F.Cu" "F.Mask" "F.Paste")
			(net "P5E_CPU1_PE4_RX_DN<10>")
		)
		(pad "AN1" smd oval
			(at -37.425122 -12.037314 180)
			(size 0.381 0.4826)
			(drill
				(offset 0 -0.0508)
			)
			(layers "F.Cu" "F.Mask" "F.Paste")
			(net "UPI_CPU1_CPU0_P0P1_DP<12>")
		)
		(pad "AN3" smd circle
			(at -35.797236 -12.037314 270)
			(size 0.4318 0.4318)
			(layers "F.Cu" "F.Mask" "F.Paste")
			(net "PVCCFA_EHV_CPU1")
		)
		(pad "AN5" smd circle
			(at -34.169604 -12.037314 270)
			(size 0.4318 0.4318)
			(layers "F.Cu" "F.Mask" "F.Paste")
			(net "UPI_CPU0_CPU1_P1P0_DN<11>")
		)
		(pad "AN7" smd circle
			(at -32.541718 -12.037314 270)
			(size 0.4318 0.4318)
			(layers "F.Cu" "F.Mask" "F.Paste")
			(net "PVCCFA_EHV_FIVRA_CPU1")
		)
		(pad "AN9" smd circle
			(at -30.914086 -12.037314 270)
			(size 0.4318 0.4318)
			(layers "F.Cu" "F.Mask" "F.Paste")
			(net "P5E_CPU1_PE0_RX_DP<11>")
		)
		(pad "AN11" smd circle
			(at -29.2862 -12.037314 270)
			(size 0.4318 0.4318)
			(layers "F.Cu" "F.Mask" "F.Paste")
			(net "PVCCFA_EHV_FIVRA_CPU1")
		)
		(pad "AN13" smd circle
			(at -27.658314 -12.037314 270)
			(size 0.4318 0.4318)
			(layers "F.Cu" "F.Mask" "F.Paste")
			(net "P5E_CPU1_PE0_TX_DN<10>")
		)
		(pad "AN15" smd circle
			(at -26.030682 -12.037314 270)
			(size 0.4318 0.4318)
			(layers "F.Cu" "F.Mask" "F.Paste")
			(net "PVCCFA_EHV_FIVRA_CPU1")
		)
		(pad "AN17" smd circle
			(at -24.402796 -12.037314 270)
			(size 0.4318 0.4318)
			(layers "F.Cu" "F.Mask" "F.Paste")
			(net "NC_CPU1_UPI0_APROBE<0>")
		)
		(pad "AN19" smd circle
			(at -22.77491 -12.037314 270)
			(size 0.4318 0.4318)
			(layers "F.Cu" "F.Mask" "F.Paste")
			(net "M_D_CPU1_SB_DQ<31>")
		)
		(pad "AN21" smd circle
			(at -21.147278 -12.037314 270)
			(size 0.4318 0.4318)
			(layers "F.Cu" "F.Mask" "F.Paste")
			(net "M_D_CPU1_SB_DQS_DN<8>")
		)
		(pad "AN23" smd circle
			(at -19.519392 -12.037314 270)
			(size 0.4318 0.4318)
			(layers "F.Cu" "F.Mask" "F.Paste")
			(net "M_D_CPU1_SB_DQ<26>")
		)
		(pad "AN25" smd circle
			(at -17.89176 -12.037314 270)
			(size 0.4318 0.4318)
			(layers "F.Cu" "F.Mask" "F.Paste")
			(net "M_D_CPU1_SB_DQ<15>")
		)
		(pad "AN27" smd circle
			(at -16.263874 -12.037314 270)
			(size 0.4318 0.4318)
			(layers "F.Cu" "F.Mask" "F.Paste")
			(net "M_D_CPU1_SB_DQS_DN<6>")
		)
		(pad "AN29" smd circle
			(at -14.635988 -12.037314 270)
			(size 0.4318 0.4318)
			(layers "F.Cu" "F.Mask" "F.Paste")
			(net "M_D_CPU1_SB_DQ<10>")
		)
		(pad "AN31" smd circle
			(at -13.008356 -12.037314 270)
			(size 0.4318 0.4318)
			(layers "F.Cu" "F.Mask" "F.Paste")
			(net "M_D_CPU1_SB_DQ<7>")
		)
		(pad "AN33" smd circle
			(at -11.380724 -12.037314 270)
			(size 0.4318 0.4318)
			(layers "F.Cu" "F.Mask" "F.Paste")
			(net "M_D_CPU1_SB_DQS_DN<5>")
		)
		(pad "AN35" smd circle
			(at -9.752838 -12.037314 270)
			(size 0.4318 0.4318)
			(layers "F.Cu" "F.Mask" "F.Paste")
			(net "M_D_CPU1_SB_DQ<2>")
		)
		(pad "AN37" smd circle
			(at -8.124952 -12.037314 270)
			(size 0.4318 0.4318)
			(layers "F.Cu" "F.Mask" "F.Paste")
			(net "M_D_CPU1_SB_CB<3>")
		)
		(pad "AN39" smd circle
			(at -6.49732 -12.037314 270)
			(size 0.4318 0.4318)
			(layers "F.Cu" "F.Mask" "F.Paste")
			(net "M_D_CPU1_SB_DQS_DP<4>")
		)
		(pad "AN41" smd circle
			(at -4.869434 -12.037314 270)
			(size 0.4318 0.4318)
			(layers "F.Cu" "F.Mask" "F.Paste")
			(net "M_D_CPU1_SB_CB<6>")
		)
		(pad "AN43" smd circle
			(at -3.241802 -12.037314 270)
			(size 0.4318 0.4318)
			(layers "F.Cu" "F.Mask" "F.Paste")
			(net "M_D_CPU1_SA_CA<6>")
		)
		(pad "AN45" smd circle
			(at -1.613916 -12.037314 270)
			(size 0.4318 0.4318)
			(layers "F.Cu" "F.Mask" "F.Paste")
			(net "M_D_CPU1_CLK_DN<1>")
		)
		(pad "AN48" smd circle
			(at 2.427732 -11.927332 270)
			(size 0.4318 0.4318)
			(layers "F.Cu" "F.Mask" "F.Paste")
			(net "M_B_CPU1_SB_RSP<0>")
		)
		(pad "AN50" smd circle
			(at 4.055618 -11.927332 270)
			(size 0.4318 0.4318)
			(layers "F.Cu" "F.Mask" "F.Paste")
			(net "M_D_CPU1_SA_CA<5>")
		)
		(pad "AN52" smd circle
			(at 5.68325 -11.927332 270)
			(size 0.4318 0.4318)
			(layers "F.Cu" "F.Mask" "F.Paste")
			(net "GND")
		)
		(pad "AN54" smd circle
			(at 7.311136 -11.927332 270)
			(size 0.4318 0.4318)
			(layers "F.Cu" "F.Mask" "F.Paste")
			(net "M_D_CPU1_SA_CS_N<2>")
		)
		(pad "AN56" smd circle
			(at 8.939022 -11.927332 270)
			(size 0.4318 0.4318)
			(layers "F.Cu" "F.Mask" "F.Paste")
			(net "M_D_CPU1_SA_CB<7>")
		)
		(pad "AN58" smd circle
			(at 10.566654 -11.927332 270)
			(size 0.4318 0.4318)
			(layers "F.Cu" "F.Mask" "F.Paste")
			(net "M_D_CPU1_SA_DQS_DN<9>")
		)
		(pad "AN60" smd circle
			(at 12.19454 -11.927332 270)
			(size 0.4318 0.4318)
			(layers "F.Cu" "F.Mask" "F.Paste")
			(net "M_D_CPU1_SA_CB<2>")
		)
		(pad "AN62" smd circle
			(at 13.822426 -11.927332 270)
			(size 0.4318 0.4318)
			(layers "F.Cu" "F.Mask" "F.Paste")
			(net "M_D_CPU1_SA_DQ<31>")
		)
		(pad "AN64" smd circle
			(at 15.450058 -11.927332 270)
			(size 0.4318 0.4318)
			(layers "F.Cu" "F.Mask" "F.Paste")
			(net "M_D_CPU1_SA_DQS_DN<8>")
		)
		(pad "AN66" smd circle
			(at 17.07769 -11.927332 270)
			(size 0.4318 0.4318)
			(layers "F.Cu" "F.Mask" "F.Paste")
			(net "M_D_CPU1_SA_DQ<26>")
		)
		(pad "AN68" smd circle
			(at 18.705576 -11.927332 270)
			(size 0.4318 0.4318)
			(layers "F.Cu" "F.Mask" "F.Paste")
			(net "M_D_CPU1_SA_DQ<23>")
		)
		(pad "AN70" smd circle
			(at 20.333462 -11.927332 270)
			(size 0.4318 0.4318)
			(layers "F.Cu" "F.Mask" "F.Paste")
			(net "M_D_CPU1_SA_DQS_DN<7>")
		)
		(pad "AN72" smd circle
			(at 21.961094 -11.927332 270)
			(size 0.4318 0.4318)
			(layers "F.Cu" "F.Mask" "F.Paste")
			(net "M_D_CPU1_SA_DQ<18>")
		)
		(pad "AN74" smd circle
			(at 23.58898 -11.927332 270)
			(size 0.4318 0.4318)
			(layers "F.Cu" "F.Mask" "F.Paste")
			(net "M_D_CPU1_SA_DQ<15>")
		)
		(pad "AN76" smd circle
			(at 25.216612 -11.927332 270)
			(size 0.4318 0.4318)
			(layers "F.Cu" "F.Mask" "F.Paste")
			(net "M_D_CPU1_SA_DQS_DN<6>")
		)
		(pad "AN78" smd circle
			(at 26.844498 -11.927332 270)
			(size 0.4318 0.4318)
			(layers "F.Cu" "F.Mask" "F.Paste")
			(net "M_D_CPU1_SA_DQ<10>")
		)
		(pad "AN80" smd circle
			(at 28.472384 -11.927332 270)
			(size 0.4318 0.4318)
			(layers "F.Cu" "F.Mask" "F.Paste")
			(net "PVCCFA_EHV_FIVRA_CPU1")
		)
		(pad "AN82" smd circle
			(at 30.100016 -11.927332 270)
			(size 0.4318 0.4318)
			(layers "F.Cu" "F.Mask" "F.Paste")
			(net "UPI_CPU1_CPU0_P2P2_DN<13>")
		)
		(pad "AN84" smd circle
			(at 31.727902 -11.927332 270)
			(size 0.4318 0.4318)
			(layers "F.Cu" "F.Mask" "F.Paste")
			(net "GND")
		)
		(pad "AN86" smd circle
			(at 33.355534 -11.927332 270)
			(size 0.4318 0.4318)
			(layers "F.Cu" "F.Mask" "F.Paste")
			(net "P5E_CPU1_PE4_TX_DP<11>")
		)
		(pad "AN88" smd circle
			(at 34.98342 -11.927332 270)
			(size 0.4318 0.4318)
			(layers "F.Cu" "F.Mask" "F.Paste")
			(net "GND")
		)
		(pad "AN90" smd circle
			(at 36.611306 -11.927332 270)
			(size 0.4318 0.4318)
			(layers "F.Cu" "F.Mask" "F.Paste")
			(net "P5E_CPU1_PE4_RX_DP<11>")
		)
		(pad "AP2" smd circle
			(at -36.611306 -11.567668 270)
			(size 0.4318 0.4318)
			(layers "F.Cu" "F.Mask" "F.Paste")
			(net "UPI_CPU1_CPU0_P0P1_DN<12>")
		)
		(pad "AP4" smd circle
			(at -34.98342 -11.567668 270)
			(size 0.4318 0.4318)
			(layers "F.Cu" "F.Mask" "F.Paste")
			(net "GND")
		)
		(pad "AP6" smd circle
			(at -33.355534 -11.567668 270)
			(size 0.4318 0.4318)
			(layers "F.Cu" "F.Mask" "F.Paste")
			(net "UPI_CPU0_CPU1_P1P0_DN<12>")
		)
		(pad "AP8" smd circle
			(at -31.727902 -11.567668 270)
			(size 0.4318 0.4318)
			(layers "F.Cu" "F.Mask" "F.Paste")
			(net "GND")
		)
		(pad "AP10" smd circle
			(at -30.100016 -11.567668 270)
			(size 0.4318 0.4318)
			(layers "F.Cu" "F.Mask" "F.Paste")
			(net "P5E_CPU1_PE0_RX_DN<12>")
		)
		(pad "AP12" smd circle
			(at -28.472384 -11.567668 270)
			(size 0.4318 0.4318)
			(layers "F.Cu" "F.Mask" "F.Paste")
			(net "GND")
		)
		(pad "AP14" smd circle
			(at -26.844498 -11.567668 270)
			(size 0.4318 0.4318)
			(layers "F.Cu" "F.Mask" "F.Paste")
			(net "P5E_CPU1_PE0_TX_DN<11>")
		)
		(pad "AP16" smd circle
			(at -25.216612 -11.567668 270)
			(size 0.4318 0.4318)
			(layers "F.Cu" "F.Mask" "F.Paste")
			(net "GND")
		)
		(pad "AP18" smd circle
			(at -23.58898 -11.567668 270)
			(size 0.4318 0.4318)
			(layers "F.Cu" "F.Mask" "F.Paste")
			(net "GND")
		)
		(pad "AP20" smd circle
			(at -21.961094 -11.567668 270)
			(size 0.4318 0.4318)
			(layers "F.Cu" "F.Mask" "F.Paste")
			(net "M_D_CPU1_SB_DQ<30>")
		)
		(pad "AP22" smd circle
			(at -20.333462 -11.567668 270)
			(size 0.4318 0.4318)
			(layers "F.Cu" "F.Mask" "F.Paste")
			(net "M_D_CPU1_SB_DQ<27>")
		)
		(pad "AP24" smd circle
			(at -18.705576 -11.567668 270)
			(size 0.4318 0.4318)
			(layers "F.Cu" "F.Mask" "F.Paste")
			(net "GND")
		)
		(pad "AP26" smd circle
			(at -17.07769 -11.567668 270)
			(size 0.4318 0.4318)
			(layers "F.Cu" "F.Mask" "F.Paste")
			(net "M_D_CPU1_SB_DQ<14>")
		)
		(pad "AP28" smd circle
			(at -15.450058 -11.567668 270)
			(size 0.4318 0.4318)
			(layers "F.Cu" "F.Mask" "F.Paste")
			(net "M_D_CPU1_SB_DQ<11>")
		)
		(pad "AP30" smd circle
			(at -13.822426 -11.567668 270)
			(size 0.4318 0.4318)
			(layers "F.Cu" "F.Mask" "F.Paste")
			(net "GND")
		)
		(pad "AP32" smd circle
			(at -12.19454 -11.567668 270)
			(size 0.4318 0.4318)
			(layers "F.Cu" "F.Mask" "F.Paste")
			(net "M_D_CPU1_SB_DQ<6>")
		)
		(pad "AP34" smd circle
			(at -10.566654 -11.567668 270)
			(size 0.4318 0.4318)
			(layers "F.Cu" "F.Mask" "F.Paste")
			(net "M_D_CPU1_SB_DQ<3>")
		)
		(pad "AP36" smd circle
			(at -8.939022 -11.567668 270)
			(size 0.4318 0.4318)
			(layers "F.Cu" "F.Mask" "F.Paste")
			(net "GND")
		)
		(pad "AP38" smd circle
			(at -7.311136 -11.567668 270)
			(size 0.4318 0.4318)
			(layers "F.Cu" "F.Mask" "F.Paste")
			(net "M_D_CPU1_SB_CB<2>")
		)
		(pad "AP40" smd circle
			(at -5.68325 -11.567668 270)
			(size 0.4318 0.4318)
			(layers "F.Cu" "F.Mask" "F.Paste")
			(net "M_D_CPU1_SB_CB<7>")
		)
		(pad "AP42" smd circle
			(at -4.055618 -11.567668 270)
			(size 0.4318 0.4318)
			(layers "F.Cu" "F.Mask" "F.Paste")
			(net "GND")
		)
		(pad "AP44" smd circle
			(at -2.427732 -11.567668 270)
			(size 0.4318 0.4318)
			(layers "F.Cu" "F.Mask" "F.Paste")
			(net "M_D_CPU1_SA_PAR")
		)
		(pad "AP47" smd circle
			(at 1.613916 -11.457686 270)
			(size 0.4318 0.4318)
			(layers "F.Cu" "F.Mask" "F.Paste")
			(net "M_B_CPU1_SB_RSP<1>")
		)
		(pad "AP49" smd circle
			(at 3.241802 -11.457686 270)
			(size 0.4318 0.4318)
			(layers "F.Cu" "F.Mask" "F.Paste")
			(net "GND")
		)
		(pad "AP51" smd circle
			(at 4.869434 -11.457686 270)
			(size 0.4318 0.4318)
			(layers "F.Cu" "F.Mask" "F.Paste")
			(net "M_D_CPU1_SA_CA<3>")
		)
		(pad "AP53" smd circle
			(at 6.49732 -11.457686 270)
			(size 0.4318 0.4318)
			(layers "F.Cu" "F.Mask" "F.Paste")
			(net "M_D_CPU1_SA_CS_N<3>")
		)
		(pad "AP55" smd circle
			(at 8.124952 -11.457686 270)
			(size 0.4318 0.4318)
			(layers "F.Cu" "F.Mask" "F.Paste")
			(net "GND")
		)
		(pad "AP57" smd circle
			(at 9.752838 -11.457686 270)
			(size 0.4318 0.4318)
			(layers "F.Cu" "F.Mask" "F.Paste")
			(net "M_D_CPU1_SA_CB<6>")
		)
		(pad "AP59" smd circle
			(at 11.380724 -11.457686 270)
			(size 0.4318 0.4318)
			(layers "F.Cu" "F.Mask" "F.Paste")
			(net "M_D_CPU1_SA_CB<3>")
		)
	)
)
